# S9S_MB_2U (Grand Teton) — schematic netlist excerpt (pin names and nets, part order shuffled) for the footprints in the layout excerpt that follows; sources: Cadence DE-HDL packaged netlist, KiCad conversion of 03242023_DA0F0TMBIJ0_F0T_Motherboard_J_brd_V01_OCP.brd

R1832  Q_RES  0 5% EMPTY  pkg 0402LF  page 239 : A = JTAG_BMC_DBP_PREQ_N ; B = JTAG_DBP_BMC_PREQ_R_N

(kicad_pcb
	(version 20260206)
	(generator "pcbnew")
	(generator_version "10.0")
	(general
		(thickness 1.6)
		(legacy_teardrops no)
	)
	(paper "A4")
	(title_block
		(title "03242023_DA0F0TMBIJ0_F0T_Motherboard_J_brd_V01_OCP.brd")
		(comment 1 "Grand Teton / footprints 3698-3698 of 6105")
	)
	(layers
		(0 "F.Cu" signal "TOP")
		(4 "In1.Cu" signal "GND")
		(6 "In2.Cu" signal "IN1")
		(8 "In3.Cu" signal "GND1")
		(10 "In4.Cu" signal "IN2")
		(12 "In5.Cu" signal "GND2")
		(14 "In6.Cu" signal "IN3")
		(16 "In7.Cu" signal "GND3")
		(18 "In8.Cu" signal "VCC")
		(20 "In9.Cu" signal "VCC1")
		(22 "In10.Cu" signal "GND4")
		(24 "In11.Cu" signal "IN4")
		(26 "In12.Cu" signal "GND5")
		(28 "In13.Cu" signal "IN5")
		(30 "In14.Cu" signal "GND6")
		(32 "In15.Cu" signal "IN6")
		(34 "In16.Cu" signal "GND7")
		(2 "B.Cu" signal "BOTTOM")
		(9 "F.Adhes" user "F.Adhesive")
		(11 "B.Adhes" user "B.Adhesive")
		(13 "F.Paste" user "Package Geometry/Pastemask Top")
		(15 "B.Paste" user "Package Geometry/Pastemask Bottom")
		(5 "F.SilkS" user "Ref Des/Silkscreen Top")
		(7 "B.SilkS" user "Ref Des/Silkscreen Bottom")
		(1 "F.Mask" user "Board Geometry/Soldermask Top")
		(3 "B.Mask" user "Board Geometry/Soldermask Bottom")
		(17 "Dwgs.User" user "User.Drawings")
		(19 "Cmts.User" user "User.Comments")
		(21 "Eco1.User" user "User.Eco1")
		(23 "Eco2.User" user "User.Eco2")
		(25 "Edge.Cuts" user "Board Geometry/Outline")
		(27 "Margin" user)
		(31 "F.CrtYd" user "Package Geometry/Place Bound Top")
		(29 "B.CrtYd" user "Package Geometry/Place Bound Bottom")
		(35 "F.Fab" user "Ref Des/Assembly Top")
		(33 "B.Fab" user "Ref Des/Assembly Bottom")
	)
	(footprint ""
		(layer "F.Cu")
		(at 370.021358 -107.333034 90)
		(property "Reference" "R1832"
			(at 0 0 90)
			(layer "F.SilkS")
			(hide yes)
			(effects
				(font
					(size 1.27 1.27)
				)
			)
		)
		(property "Value" ""
			(at 0 0 90)
			(layer "F.Fab")
			(effects
				(font
					(size 1.27 1.27)
				)
			)
		)
		(duplicate_pad_numbers_are_jumpers no)
		(fp_line
			(start 0.7874 -0.4064)
			(end 0.7874 0.4064)
			(stroke
				(width 0.1524)
				(type default)
			)
			(layer "F.SilkS")
		)
		(fp_line
			(start -0.7874 -0.4064)
			(end 0.7874 -0.4064)
			(stroke
				(width 0.1524)
				(type default)
			)
			(layer "F.SilkS")
		)
		(fp_line
			(start 0.7874 0.4064)
			(end -0.7874 0.4064)
			(stroke
				(width 0.1524)
				(type default)
			)
			(layer "F.SilkS")
		)
		(fp_line
			(start -0.7874 0.4064)
			(end -0.7874 -0.4064)
			(stroke
				(width 0.1524)
				(type default)
			)
			(layer "F.SilkS")
		)
		(fp_line
			(start -0.12065 -0.305054)
			(end -0.12065 -0.2794)
			(stroke
				(width 0.1)
				(type default)
			)
			(layer "F.Fab")
		)
		(fp_line
			(start -0.67945 -0.305054)
			(end -0.12065 -0.305054)
			(stroke
				(width 0.1)
				(type default)
			)
			(layer "F.Fab")
		)
		(fp_line
			(start 0.67945 -0.3048)
			(end 0.67945 0.3048)
			(stroke
				(width 0.1)
				(type default)
			)
			(layer "F.Fab")
		)
		(fp_line
			(start 0.12065 -0.3048)
			(end 0.67945 -0.3048)
			(stroke
				(width 0.1)
				(type default)
			)
			(layer "F.Fab")
		)
		(fp_line
			(start 0.12065 -0.2794)
			(end 0.12065 -0.3048)
			(stroke
				(width 0.1)
				(type default)
			)
			(layer "F.Fab")
		)
		(fp_line
			(start -0.12065 -0.2794)
			(end 0.12065 -0.2794)
			(stroke
				(width 0.1)
				(type default)
			)
			(layer "F.Fab")
		)
		(fp_line
			(start 0.120396 0.2794)
			(end -0.12065 0.2794)
			(stroke
				(width 0.1)
				(type default)
			)
			(layer "F.Fab")
		)
		(fp_line
			(start -0.12065 0.2794)
			(end -0.12065 0.3048)
			(stroke
				(width 0.1)
				(type default)
			)
			(layer "F.Fab")
		)
		(fp_line
			(start 0.67945 0.3048)
			(end 0.120396 0.3048)
			(stroke
				(width 0.1)
				(type default)
			)
			(layer "F.Fab")
		)
		(fp_line
			(start 0.120396 0.3048)
			(end 0.120396 0.2794)
			(stroke
				(width 0.1)
				(type default)
			)
			(layer "F.Fab")
		)
		(fp_line
			(start -0.12065 0.3048)
			(end -0.67945 0.3048)
			(stroke
				(width 0.1)
				(type default)
			)
			(layer "F.Fab")
		)
		(fp_line
			(start -0.67945 0.3048)
			(end -0.67945 -0.305054)
			(stroke
				(width 0.1)
				(type default)
			)
			(layer "F.Fab")
		)
		(pad "1" smd circle
			(at -0.40005 0 90)
			(size 0 0)
			(layers "F.Cu" "F.Mask" "F.Paste")
			(net "JTAG_BMC_DBP_PREQ_N")
		)
		(pad "2" smd circle
			(at 0.40005 0 90)
			(size 0 0)
			(layers "F.Cu" "F.Mask" "F.Paste")
			(net "JTAG_DBP_BMC_PREQ_R_N")
		)
	)
)
